# T6G (Grand Teton) — schematic parts with pin connectivity, parts 2599–2599 of 8303; source: Cadence DE-HDL packaged netlist (pstxprt.dat, pstxnet.dat, pstchip.dat)

J17  SCONN288_DDR506112002KQ  IO  pkg DDR288S_1-1VXC  page 88
  1  VIN_BULK0  POWER  = P12V_MEM_CPU0
  2  RFU0  TRI  = NC
  3  VIN_MGMT  POWER  = P3V3_AUX
  4  HSCL  IN  = I3C_SPD_DDRC_CPU0_SCL
  5  HSDA  BI  = I3C_SPD_DDRC_CPU0_SDA
  6  VSS0  POWER  = GND
  7  DQ0_A  BI  = M_C_CPU0_SA_DQ<0>
  8  VSS1  POWER  = GND
  9  DQ1_A  BI  = M_C_CPU0_SA_DQ<1>
  10  VSS2  POWER  = GND
  11  DQS0_A_T  BI  = M_C_CPU0_SA_DQS_DP<0>
  12  DQS0_A_C  BI  = M_C_CPU0_SA_DQS_DN<0>
  13  VSS3  POWER  = GND
  14  DQ4_A  BI  = M_C_CPU0_SA_DQ<4>
  15  VSS4  POWER  = GND
  16  DQ5_A  BI  = M_C_CPU0_SA_DQ<5>
  17  VSS5  POWER  = GND
  18  DQ8_A  BI  = M_C_CPU0_SA_DQ<8>
  19  VSS6  POWER  = GND
  20  DQ9_A  BI  = M_C_CPU0_SA_DQ<9>
  21  VSS7  POWER  = GND
  22  DQS1_A_T  BI  = M_C_CPU0_SA_DQS_DP<1>
  23  DQS1_A_C  BI  = M_C_CPU0_SA_DQS_DN<1>
  24  VSS8  POWER  = GND
  25  DQ12_A  BI  = M_C_CPU0_SA_DQ<12>
  26  VSS9  POWER  = GND
  27  DQ13_A  BI  = M_C_CPU0_SA_DQ<13>
  28  VSS10  POWER  = GND
  29  DQ16_A  BI  = M_C_CPU0_SA_DQ<16>
  30  VSS11  POWER  = GND
  31  DQ17_A  BI  = M_C_CPU0_SA_DQ<17>
  32  VSS12  POWER  = GND
  33  DQS2_A_T  BI  = M_C_CPU0_SA_DQS_DP<2>
  34  DQS2_A_C  BI  = M_C_CPU0_SA_DQS_DN<2>
  35  VSS13  POWER  = GND
  36  DQ20_A  BI  = M_C_CPU0_SA_DQ<20>
  37  VSS14  POWER  = GND
  38  DQ21_A  BI  = M_C_CPU0_SA_DQ<21>
  39  VSS15  POWER  = GND
  40  DQ24_A  BI  = M_C_CPU0_SA_DQ<24>
  41  VSS16  POWER  = GND
  42  DQ25_A  BI  = M_C_CPU0_SA_DQ<25>
  43  VSS17  POWER  = GND
  44  DQS3_A_T  BI  = M_C_CPU0_SA_DQS_DP<3>
  45  DQS3_A_C  BI  = M_C_CPU0_SA_DQS_DN<3>
  46  VSS18  POWER  = GND
  47  DQ28_A  BI  = M_C_CPU0_SA_DQ<28>
  48  VSS19  POWER  = GND
  49  DQ29_A  BI  = M_C_CPU0_SA_DQ<29>
  50  VSS20  POWER  = GND
  51  CB0_A  BI  = M_C_CPU0_SA_CB<0>
  52  VSS21  POWER  = GND
  53  CB1_A  BI  = M_C_CPU0_SA_CB<1>
  54  VSS22  POWER  = GND
  55  DQS4_A_T  BI  = M_C_CPU0_SA_DQS_DP<4>
  56  DQS4_A_C  BI  = M_C_CPU0_SA_DQS_DN<4>
  57  VSS23  POWER  = GND
  58  CB4_A  BI  = M_C_CPU0_SA_CB<4>
  59  VSS24  POWER  = GND
  60  CB5_A  BI  = M_C_CPU0_SA_CB<5>
  61  VSS25  POWER  = GND
  62  ALERT_N  OUT  = M_C_CPU0_ALERT_N
  63  VSS26  POWER  = GND
  64  CS0_A_N  IN  = M_C_CPU0_SA_CS_N<0>
  65  VSS27  POWER  = GND
  66  CA0_A  IN  = M_C_CPU0_SA_CA<0>
  67  VSS28  POWER  = GND
  68  CA2_A  IN  = M_C_CPU0_SA_CA<2>
  69  VSS29  POWER  = GND
  70  CA4_A  IN  = M_C_CPU0_SA_CA<4>
  71  VSS30  POWER  = GND
  72  CA6_A  IN  = M_C_CPU0_SA_CA<6>
  73  VSS31  POWER  = GND
  74  PAR_A  IN  = M_C_CPU0_SA_PAR
  75  VSS32  POWER  = GND
  76  CA0_B  IN  = M_C_CPU0_SB_CA<0>
  77  VSS33  POWER  = GND
  78  CA2_B  IN  = M_C_CPU0_SB_CA<2>
  79  VSS34  POWER  = GND
  80  CA4_B  IN  = M_C_CPU0_SB_CA<4>
  81  VSS35  POWER  = GND
  82  CA6_B  IN  = M_C_CPU0_SB_CA<6>
  83  VSS36  POWER  = GND
  84  CS0_B_N  IN  = M_C_CPU0_SB_CS_N<0>
  85  VSS37  POWER  = GND
  86  \lbd||rsp_a_n\  OUT  = M_C_CPU0_SA_RSP<0>
  87  \lbs||rsp_b_n\  OUT  = M_C_CPU0_SB_RSP<0>
  88  VSS38  POWER  = GND
  89  CB4_B  BI  = M_C_CPU0_SB_CB<4>
  90  VSS39  POWER  = GND
  91  CB5_B  BI  = M_C_CPU0_SB_CB<5>
  92  VSS40  POWER  = GND
  93  \dqs9_b_t||tdqs9_b_t||dbi4_b_n\  BI  = M_C_CPU0_SB_DQS_DP<9>
  94  \dqs9_b_c||tdqs9_b_c\  BI  = M_C_CPU0_SB_DQS_DN<9>
  95  VSS41  POWER  = GND
  96  CB0_B  BI  = M_C_CPU0_SB_CB<0>
  97  VSS42  POWER  = GND
  98  CB1_B  BI  = M_C_CPU0_SB_CB<1>
  99  VSS43  POWER  = GND
  100  DQ0_B  BI  = M_C_CPU0_SB_DQ<0>
  101  VSS44  POWER  = GND
  102  DQ1_B  BI  = M_C_CPU0_SB_DQ<1>
  103  VSS45  POWER  = GND
  104  DQS0_B_T  BI  = M_C_CPU0_SB_DQS_DP<0>
  105  DQS0_B_C  BI  = M_C_CPU0_SB_DQS_DN<0>
  106  VSS46  POWER  = GND
  107  DQ4_B  BI  = M_C_CPU0_SB_DQ<4>
  108  VSS47  POWER  = GND
  109  DQ5_B  BI  = M_C_CPU0_SB_DQ<5>
  110  VSS48  POWER  = GND
  111  DQ8_B  BI  = M_C_CPU0_SB_DQ<8>
  112  VSS49  POWER  = GND
  113  DQ9_B  BI  = M_C_CPU0_SB_DQ<9>
  114  VSS50  POWER  = GND
  115  DQS1_B_T  BI  = M_C_CPU0_SB_DQS_DP<1>
  116  DQS1_B_C  BI  = M_C_CPU0_SB_DQS_DN<1>
  117  VSS51  POWER  = GND
  118  DQ12_B  BI  = M_C_CPU0_SB_DQ<12>
  119  VSS52  POWER  = GND
  120  DQ13_B  BI  = M_C_CPU0_SB_DQ<13>
  121  VSS53  POWER  = GND
  122  DQ16_B  BI  = M_C_CPU0_SB_DQ<16>
  123  VSS54  POWER  = GND
  124  DQ17_B  BI  = M_C_CPU0_SB_DQ<17>
  125  VSS55  POWER  = GND
  126  DQS2_B_T  BI  = M_C_CPU0_SB_DQS_DP<2>
  127  DQS2_B_C  BI  = M_C_CPU0_SB_DQS_DN<2>
  128  VSS56  POWER  = GND
  129  DQ20_B  BI  = M_C_CPU0_SB_DQ<20>
  130  VSS57  POWER  = GND
  131  DQ21_B  BI  = M_C_CPU0_SB_DQ<21>
  132  VSS58  POWER  = GND
  133  DQ24_B  BI  = M_C_CPU0_SB_DQ<24>
  134  VSS59  POWER  = GND
  135  DQ25_B  BI  = M_C_CPU0_SB_DQ<25>
  136  VSS60  POWER  = GND
  137  DQS3_B_T  BI  = M_C_CPU0_SB_DQS_DP<3>
  138  DQS3_B_C  BI  = M_C_CPU0_SB_DQS_DN<3>
  139  VSS61  POWER  = GND
  140  DQ28_B  BI  = M_C_CPU0_SB_DQ<28>
  141  VSS62  POWER  = GND
  142  DQ29_B  BI  = M_C_CPU0_SB_DQ<29>
  143  VSS63  POWER  = GND
  144  RFU1  TRI  = NC
  145  VIN_BULK1  POWER  = P12V_MEM_CPU0
  146  VIN_BULK2  POWER  = P12V_MEM_CPU0
  147  \pwr_good||fail_n\  BI  = PWRGD_CHC_CPU0_DIMM
  148  HAS  IN  = PD_CHC_CPU0_DIMM_SAA
  149  RFU2  TRI  = NC
  150  RFU3  TRI  = NC
  151  VSS64  POWER  = GND
  152  DQ2_A  BI  = M_C_CPU0_SA_DQ<2>
  153  VSS65  POWER  = GND
  154  DQ3_A  BI  = M_C_CPU0_SA_DQ<3>
  155  VSS66  POWER  = GND
  156  \dqs5_a_c||tdqs5_a_c||dqs5_a_t||tdqs5_a_t\  BI  = M_C_CPU0_SA_DQS_DN<5>
  157  \dqs5_a_t||tdqs5_a_t\  BI  = M_C_CPU0_SA_DQS_DP<5>
  158  VSS67  POWER  = GND
  159  DQ6_A  BI  = M_C_CPU0_SA_DQ<6>
  160  VSS68  POWER  = GND
  161  DQ7_A  BI  = M_C_CPU0_SA_DQ<7>
  162  VSS69  POWER  = GND
  163  DQ10_A  BI  = M_C_CPU0_SA_DQ<10>
  164  VSS70  POWER  = GND
  165  DQ11_A  BI  = M_C_CPU0_SA_DQ<11>
  166  VSS71  POWER  = GND
  167  \dqs6_a_c||tdqs6_a_c||dqs6_a_t||tdqs6_a_t\  BI  = M_C_CPU0_SA_DQS_DN<6>
  168  \dqs6_a_t||tdqs6_a_t\  BI  = M_C_CPU0_SA_DQS_DP<6>
  169  VSS72  POWER  = GND
  170  DQ14_A  BI  = M_C_CPU0_SA_DQ<14>
  171  VSS73  POWER  = GND
  172  DQ15_A  BI  = M_C_CPU0_SA_DQ<15>
  173  VSS74  POWER  = GND
  174  DQ18_A  BI  = M_C_CPU0_SA_DQ<18>
  175  VSS75  POWER  = GND
  176  DQ19_A  BI  = M_C_CPU0_SA_DQ<19>
  177  VSS76  POWER  = GND
  178  \dqs7_a_c||tdqs7_a_c\  BI  = M_C_CPU0_SA_DQS_DN<7>
  179  \dqs7_a_t||tdqs7_a_t\  BI  = M_C_CPU0_SA_DQS_DP<7>
  180  VSS77  POWER  = GND
  181  DQ22_A  BI  = M_C_CPU0_SA_DQ<22>
  182  VSS78  POWER  = GND
  183  DQ23_A  BI  = M_C_CPU0_SA_DQ<23>
  184  VSS79  POWER  = GND
  185  DQ26_A  BI  = M_C_CPU0_SA_DQ<26>
  186  VSS80  POWER  = GND
  187  DQ27_A  BI  = M_C_CPU0_SA_DQ<27>
  188  VSS81  POWER  = GND
  189  \dqs8_a_c||tdqs8_a_c\  BI  = M_C_CPU0_SA_DQS_DN<8>
  190  \dqs8_a_t||tdqs8_a_t\  BI  = M_C_CPU0_SA_DQS_DP<8>
  191  VSS82  POWER  = GND
  192  DQ30_A  BI  = M_C_CPU0_SA_DQ<30>
  193  VSS83  POWER  = GND
  194  DQ31_A  BI  = M_C_CPU0_SA_DQ<31>
  195  VSS84  POWER  = GND
  196  CB2_A  BI  = M_C_CPU0_SA_CB<2>
  197  VSS85  POWER  = GND
  198  CB3_A  BI  = M_C_CPU0_SA_CB<3>
  199  VSS86  POWER  = GND
  200  \dqs9_a_c||tdqs9_a_c\  BI  = M_C_CPU0_SA_DQS_DN<9>
  201  \dqs9_a_t||tdqs9_a_t\  BI  = M_C_CPU0_SA_DQS_DP<9>
  202  VSS87  POWER  = GND
  203  CB6_A  BI  = M_C_CPU0_SA_CB<6>
  204  VSS88  POWER  = GND
  205  CB7_A  BI  = M_C_CPU0_SA_CB<7>
  206  VSS89  POWER  = GND
  207  RESET_N  IN  = M_C_CPU0_RESET_N
  208  VSS90  POWER  = GND
  209  CS1_A_N  IN  = M_C_CPU0_SA_CS_N<1>
  210  VSS91  POWER  = GND
  211  CA1_A  IN  = M_C_CPU0_SA_CA<1>
  212  VSS92  POWER  = GND
  213  CA3_A  IN  = M_C_CPU0_SA_CA<3>
  214  VSS93  POWER  = GND
  215  CA5_A  IN  = M_C_CPU0_SA_CA<5>
  216  VSS94  POWER  = GND
  217  CK_T  IN  = M_C_CPU0_CLK_DP<0>
  218  CK_C  IN  = M_C_CPU0_CLK_DN<0>
  219  VSS95  POWER  = GND
  220  RFU4  TRI  = NC
  221  CA1_B  IN  = M_C_CPU0_SB_CA<1>
  222  VSS96  POWER  = GND
  223  CA3_B  IN  = M_C_CPU0_SB_CA<3>
  224  VSS97  POWER  = GND
  225  CA5_B  IN  = M_C_CPU0_SB_CA<5>
  226  VSS98  POWER  = GND
  227  PAR_B  IN  = M_C_CPU0_SB_PAR
  228  VSS99  POWER  = GND
  229  CS1_B_N  IN  = M_C_CPU0_SB_CS_N<1>
  230  VSS100  POWER  = GND
  231  RFU5  TRI  = NC
  232  RFU6  TRI  = NC
  233  VSS101  POWER  = GND
  234  CB6_B  BI  = M_C_CPU0_SB_CB<6>
  235  VSS102  POWER  = GND
  236  CB7_B  BI  = M_C_CPU0_SB_CB<7>
  237  VSS103  POWER  = GND
  238  DQS4_B_C  BI  = M_C_CPU0_SB_DQS_DN<4>
  239  DQS4_B_T  BI  = M_C_CPU0_SB_DQS_DP<4>
  240  VSS104  POWER  = GND
  241  CB2_B  BI  = M_C_CPU0_SB_CB<2>
  242  VSS105  POWER  = GND
  243  CB3_B  BI  = M_C_CPU0_SB_CB<3>
  244  VSS106  POWER  = GND
  245  DQ2_B  BI  = M_C_CPU0_SB_DQ<2>
  246  VSS107  POWER  = GND
  247  DQ3_B  BI  = M_C_CPU0_SB_DQ<3>
  248  VSS108  POWER  = GND
  249  \dqs5_b_c||tdqs5_b_c\  BI  = M_C_CPU0_SB_DQS_DN<5>
  250  \dqs5_b_t||tdqs5_b_t\  BI  = M_C_CPU0_SB_DQS_DP<5>
  251  VSS109  POWER  = GND
  252  DQ6_B  BI  = M_C_CPU0_SB_DQ<6>
  253  VSS110  POWER  = GND
  254  DQ7_B  BI  = M_C_CPU0_SB_DQ<7>
  255  VSS111  POWER  = GND
  256  DQ10_B  BI  = M_C_CPU0_SB_DQ<10>
  257  VSS112  POWER  = GND
  258  DQ11_B  BI  = M_C_CPU0_SB_DQ<11>
  259  VSS113  POWER  = GND
  260  \dqs6_b_c||tdqs6_b_c\  BI  = M_C_CPU0_SB_DQS_DN<6>
  261  \dqs6_b_t||tdqs6_b_t\  BI  = M_C_CPU0_SB_DQS_DP<6>
  262  VSS114  POWER  = GND
  263  DQ14_B  BI  = M_C_CPU0_SB_DQ<14>
  264  VSS115  POWER  = GND
  265  DQ15_B  BI  = M_C_CPU0_SB_DQ<15>
  266  VSS116  POWER  = GND
  267  DQ18_B  BI  = M_C_CPU0_SB_DQ<18>
  268  VSS117  POWER  = GND
  269  DQ19_B  BI  = M_C_CPU0_SB_DQ<19>
  270  VSS118  POWER  = GND
  271  \dqs7_b_c||tdqs7_b_c\  BI  = M_C_CPU0_SB_DQS_DN<7>
  272  \dqs7_b_t||tdqs7_b_t\  BI  = M_C_CPU0_SB_DQS_DP<7>
  273  VSS119  POWER  = GND
  274  DQ22_B  BI  = M_C_CPU0_SB_DQ<22>
  275  VSS120  POWER  = GND
  276  DQ23_B  BI  = M_C_CPU0_SB_DQ<23>
  277  VSS121  POWER  = GND
  278  DQ26_B  BI  = M_C_CPU0_SB_DQ<26>
  279  VSS122  POWER  = GND
  280  DQ27_B  BI  = M_C_CPU0_SB_DQ<27>
  281  VSS123  POWER  = GND
  282  \dqs8_b_c||tdqs8_b_c\  BI  = M_C_CPU0_SB_DQS_DN<8>
  283  \dqs8_b_t||tdqs8_b_t\  BI  = M_C_CPU0_SB_DQS_DP<8>
  284  VSS124  POWER  = GND
  285  DQ30_B  BI  = M_C_CPU0_SB_DQ<30>
  286  VSS125  POWER  = GND
  287  DQ31_B  BI  = M_C_CPU0_SB_DQ<31>
  288  VSS126  POWER  = GND
  G1  G1  POWER  = GND
  G2  G2  POWER  = GND
  G3  G3  POWER  = GND
